(kicad_pcb
	(version 20260206)
	(generator "pcbnew")
	(generator_version "10.0")
	(general
		(thickness 1.6)
		(legacy_teardrops no)
	)
	(paper "A4")
	(title_block
		(title "Wiwynn_Tioga_Pass_MB.brd")
		(comment 1 "Tioga Pass / footprint 368 of 4770 (J9B3), pads 1-117 of 122")
	)
	(layers
		(0 "F.Cu" signal "TOP")
		(4 "In1.Cu" signal "L2GND")
		(6 "In2.Cu" signal "L3")
		(8 "In3.Cu" signal "L4GND")
		(10 "In4.Cu" signal "L5")
		(12 "In5.Cu" signal "L6GND")
		(14 "In6.Cu" signal "L7VCC")
		(16 "In7.Cu" signal "L8VCC")
		(18 "In8.Cu" signal "L9GND")
		(20 "In9.Cu" signal "L10")
		(22 "In10.Cu" signal "L11GND")
		(24 "In11.Cu" signal "L12")
		(26 "In12.Cu" signal "L13GND")
		(2 "B.Cu" signal "BOTTOM")
		(9 "F.Adhes" user "F.Adhesive")
		(11 "B.Adhes" user "B.Adhesive")
		(13 "F.Paste" user "Package Geometry/Pastemask Top")
		(15 "B.Paste" user "Package Geometry/Pastemask Bottom")
		(5 "F.SilkS" user "Ref Des/Silkscreen Top")
		(7 "B.SilkS" user "Ref Des/Silkscreen Bottom")
		(1 "F.Mask" user "Board Geometry/Soldermask Top")
		(3 "B.Mask" user "Board Geometry/Soldermask Bottom")
		(17 "Dwgs.User" user "User.Drawings")
		(19 "Cmts.User" user "User.Comments")
		(21 "Eco1.User" user "User.Eco1")
		(23 "Eco2.User" user "User.Eco2")
		(25 "Edge.Cuts" user "Board Geometry/Outline")
		(27 "Margin" user)
		(31 "F.CrtYd" user "Package Geometry/Place Bound Top")
		(29 "B.CrtYd" user "Package Geometry/Place Bound Bottom")
		(35 "F.Fab" user "Ref Des/Assembly Top")
		(33 "B.Fab" user "Ref Des/Assembly Bottom")
	)
	(footprint ""
		(layer "F.Cu")
		(at 487.800904 -116.993162 -90)
		(property "Reference" "J9B3"
			(at -2.227072 26.281888 0)
			(unlocked yes)
			(layer "F.SilkS")
			(effects
				(font
					(size 0.7874 0.5842)
					(thickness 0.1524)
				)
			)
		)
		(property "Value" ""
			(at 0 0 270)
			(layer "F.Fab")
			(effects
				(font
					(size 1.27 1.27)
				)
			)
		)
		(duplicate_pad_numbers_are_jumpers no)
		(pad "" np_thru_hole circle
			(at 2.393696 -2.500122 270)
			(size 0.254 0.254)
			(drill 1.1938)
			(layers "*.Cu" "*.Mask")
			(clearance 0.7874)
			(thermal_gap 0.7874)
		)
		(pad "" np_thru_hole circle
			(at 2.393696 49.699926 270)
			(size 0.254 0.254)
			(drill 0.8128)
			(layers "*.Cu" "*.Mask")
			(clearance 0.5969)
			(thermal_gap 0.5969)
		)
		(pad "1" smd rect
			(at 0 0 270)
			(size 2.3876 0.508)
			(layers "F.Cu" "F.Mask" "F.Paste")
			(net "FM_MEZZA_PRSNT1_N")
		)
		(pad "2" smd rect
			(at 4.787646 0 270)
			(size 2.3876 0.508)
			(layers "F.Cu" "F.Mask" "F.Paste")
			(net "P12V_STBY")
		)
		(pad "3" smd rect
			(at 0 0.8001 270)
			(size 2.3876 0.508)
			(layers "F.Cu" "F.Mask" "F.Paste")
			(net "P5V_STBY")
		)
		(pad "4" smd rect
			(at 4.787646 0.8001 270)
			(size 2.3876 0.508)
			(layers "F.Cu" "F.Mask" "F.Paste")
			(net "P12V_STBY")
		)
		(pad "5" smd rect
			(at 0 1.599946 270)
			(size 2.3876 0.508)
			(layers "F.Cu" "F.Mask" "F.Paste")
			(net "P5V_STBY")
		)
		(pad "6" smd rect
			(at 4.787646 1.599946 270)
			(size 2.3876 0.508)
			(layers "F.Cu" "F.Mask" "F.Paste")
			(net "P12V_STBY")
		)
		(pad "7" smd rect
			(at 0 2.400046 270)
			(size 2.3876 0.508)
			(layers "F.Cu" "F.Mask" "F.Paste")
			(net "P5V_STBY")
		)
		(pad "8" smd rect
			(at 4.787646 2.400046 270)
			(size 2.3876 0.508)
			(layers "F.Cu" "F.Mask" "F.Paste")
			(net "GND")
		)
		(pad "9" smd rect
			(at 0 3.199892 270)
			(size 2.3876 0.508)
			(layers "F.Cu" "F.Mask" "F.Paste")
			(net "GND")
		)
		(pad "10" smd rect
			(at 4.787646 3.199892 270)
			(size 2.3876 0.508)
			(layers "F.Cu" "F.Mask" "F.Paste")
			(net "GND")
		)
		(pad "11" smd rect
			(at 0 3.999992 270)
			(size 2.3876 0.508)
			(layers "F.Cu" "F.Mask" "F.Paste")
			(net "GND")
		)
		(pad "12" smd rect
			(at 4.787646 3.999992 270)
			(size 2.3876 0.508)
			(layers "F.Cu" "F.Mask" "F.Paste")
			(net "P3V3_STBY")
		)
		(pad "13" smd rect
			(at 0 4.800092 270)
			(size 2.3876 0.508)
			(layers "F.Cu" "F.Mask" "F.Paste")
			(net "P3V3_STBY")
		)
		(pad "14" smd rect
			(at 4.787646 4.800092 270)
			(size 2.3876 0.508)
			(layers "F.Cu" "F.Mask" "F.Paste")
			(net "GND")
		)
		(pad "15" smd rect
			(at 0 5.599938 270)
			(size 2.3876 0.508)
			(layers "F.Cu" "F.Mask" "F.Paste")
			(net "GND")
		)
		(pad "16" smd rect
			(at 4.787646 5.599938 270)
			(size 2.3876 0.508)
			(layers "F.Cu" "F.Mask" "F.Paste")
			(net "GND")
		)
		(pad "17" smd rect
			(at 0 6.400038 270)
			(size 2.3876 0.508)
			(layers "F.Cu" "F.Mask" "F.Paste")
			(net "GND")
		)
		(pad "18" smd rect
			(at 4.787646 6.400038 270)
			(size 2.3876 0.508)
			(layers "F.Cu" "F.Mask" "F.Paste")
			(net "P3V3")
		)
		(pad "19" smd rect
			(at 0 7.199884 270)
			(size 2.3876 0.508)
			(layers "F.Cu" "F.Mask" "F.Paste")
			(net "P3V3")
		)
		(pad "20" smd rect
			(at 4.787646 7.199884 270)
			(size 2.3876 0.508)
			(layers "F.Cu" "F.Mask" "F.Paste")
			(net "P3V3")
		)
		(pad "21" smd rect
			(at 0 7.999984 270)
			(size 2.3876 0.508)
			(layers "F.Cu" "F.Mask" "F.Paste")
			(net "P3V3")
		)
		(pad "22" smd rect
			(at 4.787646 7.999984 270)
			(size 2.3876 0.508)
			(layers "F.Cu" "F.Mask" "F.Paste")
			(net "P3V3")
		)
		(pad "23" smd rect
			(at 0 8.800084 270)
			(size 2.3876 0.508)
			(layers "F.Cu" "F.Mask" "F.Paste")
			(net "P3V3")
		)
		(pad "24" smd rect
			(at 4.787646 8.800084 270)
			(size 2.3876 0.508)
			(layers "F.Cu" "F.Mask" "F.Paste")
			(net "P3V3")
		)
		(pad "25" smd rect
			(at 0 9.59993 270)
			(size 2.3876 0.508)
			(layers "F.Cu" "F.Mask" "F.Paste")
			(net "P3V3")
		)
		(pad "26" smd rect
			(at 4.787646 9.59993 270)
			(size 2.3876 0.508)
			(layers "F.Cu" "F.Mask" "F.Paste")
			(net "GND")
		)
		(pad "27" smd rect
			(at 0 10.40003 270)
			(size 2.3876 0.508)
			(layers "F.Cu" "F.Mask" "F.Paste")
			(net "RMII_BMC_OCP_CRSDV_R")
		)
		(pad "28" smd rect
			(at 4.787646 10.40003 270)
			(size 2.3876 0.508)
			(layers "F.Cu" "F.Mask" "F.Paste")
			(net "IRQ_MEZZ_LAN_ALERT_N")
		)
		(pad "29" smd rect
			(at 0 11.199876 270)
			(size 2.3876 0.508)
			(layers "F.Cu" "F.Mask" "F.Paste")
			(net "CLK_50M_CKMNG_OCP")
		)
		(pad "30" smd rect
			(at 4.787646 11.199876 270)
			(size 2.3876 0.508)
			(layers "F.Cu" "F.Mask" "F.Paste")
			(net "SMB_OCP_FRU_STBY_LVC3_SCL")
		)
		(pad "31" smd rect
			(at 0 11.999976 270)
			(size 2.3876 0.508)
			(layers "F.Cu" "F.Mask" "F.Paste")
			(net "RMII_BMC_OCP_TXEN")
		)
		(pad "32" smd rect
			(at 4.787646 11.999976 270)
			(size 2.3876 0.508)
			(layers "F.Cu" "F.Mask" "F.Paste")
			(net "SMB_OCP_FRU_STBY_LVC3_SDA")
		)
		(pad "33" smd rect
			(at 0 12.800076 270)
			(size 2.3876 0.508)
			(layers "F.Cu" "F.Mask" "F.Paste")
			(net "RST_PCIE_CPU_DEV0_R_N")
		)
		(pad "34" smd rect
			(at 4.787646 12.800076 270)
			(size 2.3876 0.508)
			(layers "F.Cu" "F.Mask" "F.Paste")
			(net "FM_PE_OCP_WAKE_N")
		)
		(pad "35" smd rect
			(at 0 13.599922 270)
			(size 2.3876 0.508)
			(layers "F.Cu" "F.Mask" "F.Paste")
			(net "SMB_OCP_LAN_STBY_LVC3_SCL")
		)
		(pad "36" smd rect
			(at 4.787646 13.599922 270)
			(size 2.3876 0.508)
			(layers "F.Cu" "F.Mask" "F.Paste")
			(net "RMII_BMC_OCP_RXER_R")
		)
		(pad "37" smd rect
			(at 0 14.400022 270)
			(size 2.3876 0.508)
			(layers "F.Cu" "F.Mask" "F.Paste")
			(net "SMB_OCP_LAN_STBY_LVC3_SDA")
		)
		(pad "38" smd rect
			(at 4.787646 14.400022 270)
			(size 2.3876 0.508)
			(layers "F.Cu" "F.Mask" "F.Paste")
			(net "GND")
		)
		(pad "39" smd rect
			(at 0 15.200122 270)
			(size 2.3876 0.508)
			(layers "F.Cu" "F.Mask" "F.Paste")
			(net "GND")
		)
		(pad "40" smd rect
			(at 4.787646 15.200122 270)
			(size 2.3876 0.508)
			(layers "F.Cu" "F.Mask" "F.Paste")
			(net "RMII_BMC_OCP_TXD0")
		)
		(pad "41" smd rect
			(at 0 15.999968 270)
			(size 2.3876 0.508)
			(layers "F.Cu" "F.Mask" "F.Paste")
			(net "GND")
		)
		(pad "42" smd rect
			(at 4.787646 15.999968 270)
			(size 2.3876 0.508)
			(layers "F.Cu" "F.Mask" "F.Paste")
			(net "RMII_BMC_OCP_TXD1")
		)
		(pad "43" smd rect
			(at 0 16.800068 270)
			(size 2.3876 0.508)
			(layers "F.Cu" "F.Mask" "F.Paste")
			(net "RMII_BMC_OCP_RXD0_R")
		)
		(pad "44" smd rect
			(at 4.787646 16.800068 270)
			(size 2.3876 0.508)
			(layers "F.Cu" "F.Mask" "F.Paste")
			(net "GND")
		)
		(pad "45" smd rect
			(at 0 17.599914 270)
			(size 2.3876 0.508)
			(layers "F.Cu" "F.Mask" "F.Paste")
			(net "RMII_BMC_OCP_RXD1_R")
		)
		(pad "46" smd rect
			(at 4.787646 17.599914 270)
			(size 2.3876 0.508)
			(layers "F.Cu" "F.Mask" "F.Paste")
			(net "GND")
		)
		(pad "47" smd rect
			(at 0 18.400014 270)
			(size 2.3876 0.508)
			(layers "F.Cu" "F.Mask" "F.Paste")
			(net "GND")
		)
		(pad "48" smd rect
			(at 4.787646 18.400014 270)
			(size 2.3876 0.508)
			(layers "F.Cu" "F.Mask" "F.Paste")
			(net "CLK_100M_MEZZ1_DP")
		)
		(pad "49" smd rect
			(at 0 19.200114 270)
			(size 2.3876 0.508)
			(layers "F.Cu" "F.Mask" "F.Paste")
			(net "GND")
		)
		(pad "50" smd rect
			(at 4.787646 19.200114 270)
			(size 2.3876 0.508)
			(layers "F.Cu" "F.Mask" "F.Paste")
			(net "CLK_100M_MEZZ1_DN")
		)
		(pad "51" smd rect
			(at 0 19.99996 270)
			(size 2.3876 0.508)
			(layers "F.Cu" "F.Mask" "F.Paste")
			(net "CLK_100M_MEZZ2_DP")
		)
		(pad "52" smd rect
			(at 4.787646 19.99996 270)
			(size 2.3876 0.508)
			(layers "F.Cu" "F.Mask" "F.Paste")
			(net "GND")
		)
		(pad "53" smd rect
			(at 0 20.80006 270)
			(size 2.3876 0.508)
			(layers "F.Cu" "F.Mask" "F.Paste")
			(net "CLK_100M_MEZZ2_DN")
		)
		(pad "54" smd rect
			(at 4.787646 20.80006 270)
			(size 2.3876 0.508)
			(layers "F.Cu" "F.Mask" "F.Paste")
			(net "GND")
		)
		(pad "55" smd rect
			(at 0 21.599906 270)
			(size 2.3876 0.508)
			(layers "F.Cu" "F.Mask" "F.Paste")
			(net "GND")
		)
		(pad "56" smd rect
			(at 4.787646 21.599906 270)
			(size 2.3876 0.508)
			(layers "F.Cu" "F.Mask" "F.Paste")
			(net "P3E_OCP_CPU0_PE3_C_TXP<15>")
		)
		(pad "57" smd rect
			(at 0 22.400006 270)
			(size 2.3876 0.508)
			(layers "F.Cu" "F.Mask" "F.Paste")
			(net "GND")
		)
		(pad "58" smd rect
			(at 4.787646 22.400006 270)
			(size 2.3876 0.508)
			(layers "F.Cu" "F.Mask" "F.Paste")
			(net "P3E_OCP_CPU0_PE3_C_TXN<15>")
		)
		(pad "59" smd rect
			(at 0 23.200106 270)
			(size 2.3876 0.508)
			(layers "F.Cu" "F.Mask" "F.Paste")
			(net "P3E_CPU0_PE3_OCP_RXP<15>")
		)
		(pad "60" smd rect
			(at 4.787646 23.200106 270)
			(size 2.3876 0.508)
			(layers "F.Cu" "F.Mask" "F.Paste")
			(net "GND")
		)
		(pad "61" smd rect
			(at 0 23.999952 270)
			(size 2.3876 0.508)
			(layers "F.Cu" "F.Mask" "F.Paste")
			(net "P3E_CPU0_PE3_OCP_RXN<15>")
		)
		(pad "62" smd rect
			(at 4.787646 23.999952 270)
			(size 2.3876 0.508)
			(layers "F.Cu" "F.Mask" "F.Paste")
			(net "GND")
		)
		(pad "63" smd rect
			(at 0 24.800052 270)
			(size 2.3876 0.508)
			(layers "F.Cu" "F.Mask" "F.Paste")
			(net "GND")
		)
		(pad "64" smd rect
			(at 4.787646 24.800052 270)
			(size 2.3876 0.508)
			(layers "F.Cu" "F.Mask" "F.Paste")
			(net "P3E_OCP_CPU0_PE3_C_TXP<14>")
		)
		(pad "65" smd rect
			(at 0 25.599898 270)
			(size 2.3876 0.508)
			(layers "F.Cu" "F.Mask" "F.Paste")
			(net "GND")
		)
		(pad "66" smd rect
			(at 4.787646 25.599898 270)
			(size 2.3876 0.508)
			(layers "F.Cu" "F.Mask" "F.Paste")
			(net "P3E_OCP_CPU0_PE3_C_TXN<14>")
		)
		(pad "67" smd rect
			(at 0 26.399998 270)
			(size 2.3876 0.508)
			(layers "F.Cu" "F.Mask" "F.Paste")
			(net "P3E_CPU0_PE3_OCP_RXP<14>")
		)
		(pad "68" smd rect
			(at 4.787646 26.399998 270)
			(size 2.3876 0.508)
			(layers "F.Cu" "F.Mask" "F.Paste")
			(net "GND")
		)
		(pad "69" smd rect
			(at 0 27.200098 270)
			(size 2.3876 0.508)
			(layers "F.Cu" "F.Mask" "F.Paste")
			(net "P3E_CPU0_PE3_OCP_RXN<14>")
		)
		(pad "70" smd rect
			(at 4.787646 27.200098 270)
			(size 2.3876 0.508)
			(layers "F.Cu" "F.Mask" "F.Paste")
			(net "GND")
		)
		(pad "71" smd rect
			(at 0 27.999944 270)
			(size 2.3876 0.508)
			(layers "F.Cu" "F.Mask" "F.Paste")
			(net "GND")
		)
		(pad "72" smd rect
			(at 4.787646 27.999944 270)
			(size 2.3876 0.508)
			(layers "F.Cu" "F.Mask" "F.Paste")
			(net "P3E_OCP_CPU0_PE3_C_TXP<13>")
		)
		(pad "73" smd rect
			(at 0 28.800044 270)
			(size 2.3876 0.508)
			(layers "F.Cu" "F.Mask" "F.Paste")
			(net "GND")
		)
		(pad "74" smd rect
			(at 4.787646 28.800044 270)
			(size 2.3876 0.508)
			(layers "F.Cu" "F.Mask" "F.Paste")
			(net "P3E_OCP_CPU0_PE3_C_TXN<13>")
		)
		(pad "75" smd rect
			(at 0 29.59989 270)
			(size 2.3876 0.508)
			(layers "F.Cu" "F.Mask" "F.Paste")
			(net "P3E_CPU0_PE3_OCP_RXP<13>")
		)
		(pad "76" smd rect
			(at 4.787646 29.59989 270)
			(size 2.3876 0.508)
			(layers "F.Cu" "F.Mask" "F.Paste")
			(net "GND")
		)
		(pad "77" smd rect
			(at 0 30.39999 270)
			(size 2.3876 0.508)
			(layers "F.Cu" "F.Mask" "F.Paste")
			(net "P3E_CPU0_PE3_OCP_RXN<13>")
		)
		(pad "78" smd rect
			(at 4.787646 30.39999 270)
			(size 2.3876 0.508)
			(layers "F.Cu" "F.Mask" "F.Paste")
			(net "GND")
		)
		(pad "79" smd rect
			(at 0 31.20009 270)
			(size 2.3876 0.508)
			(layers "F.Cu" "F.Mask" "F.Paste")
			(net "GND")
		)
		(pad "80" smd rect
			(at 4.787646 31.20009 270)
			(size 2.3876 0.508)
			(layers "F.Cu" "F.Mask" "F.Paste")
			(net "P3E_OCP_CPU0_PE3_C_TXP<12>")
		)
		(pad "81" smd rect
			(at 0 31.999936 270)
			(size 2.3876 0.508)
			(layers "F.Cu" "F.Mask" "F.Paste")
			(net "GND")
		)
		(pad "82" smd rect
			(at 4.787646 31.999936 270)
			(size 2.3876 0.508)
			(layers "F.Cu" "F.Mask" "F.Paste")
			(net "P3E_OCP_CPU0_PE3_C_TXN<12>")
		)
		(pad "83" smd rect
			(at 0 32.800036 270)
			(size 2.3876 0.508)
			(layers "F.Cu" "F.Mask" "F.Paste")
			(net "P3E_CPU0_PE3_OCP_RXP<12>")
		)
		(pad "84" smd rect
			(at 4.787646 32.800036 270)
			(size 2.3876 0.508)
			(layers "F.Cu" "F.Mask" "F.Paste")
			(net "GND")
		)
		(pad "85" smd rect
			(at 0 33.599882 270)
			(size 2.3876 0.508)
			(layers "F.Cu" "F.Mask" "F.Paste")
			(net "P3E_CPU0_PE3_OCP_RXN<12>")
		)
		(pad "86" smd rect
			(at 4.787646 33.599882 270)
			(size 2.3876 0.508)
			(layers "F.Cu" "F.Mask" "F.Paste")
			(net "GND")
		)
		(pad "87" smd rect
			(at 0 34.399982 270)
			(size 2.3876 0.508)
			(layers "F.Cu" "F.Mask" "F.Paste")
			(net "GND")
		)
		(pad "88" smd rect
			(at 4.787646 34.399982 270)
			(size 2.3876 0.508)
			(layers "F.Cu" "F.Mask" "F.Paste")
			(net "P3E_OCP_CPU0_PE3_C_TXP<11>")
		)
		(pad "89" smd rect
			(at 0 35.200082 270)
			(size 2.3876 0.508)
			(layers "F.Cu" "F.Mask" "F.Paste")
			(net "GND")
		)
		(pad "90" smd rect
			(at 4.787646 35.200082 270)
			(size 2.3876 0.508)
			(layers "F.Cu" "F.Mask" "F.Paste")
			(net "P3E_OCP_CPU0_PE3_C_TXN<11>")
		)
		(pad "91" smd rect
			(at 0 35.999928 270)
			(size 2.3876 0.508)
			(layers "F.Cu" "F.Mask" "F.Paste")
			(net "P3E_CPU0_PE3_OCP_RXP<11>")
		)
		(pad "92" smd rect
			(at 4.787646 35.999928 270)
			(size 2.3876 0.508)
			(layers "F.Cu" "F.Mask" "F.Paste")
			(net "GND")
		)
		(pad "93" smd rect
			(at 0 36.800028 270)
			(size 2.3876 0.508)
			(layers "F.Cu" "F.Mask" "F.Paste")
			(net "P3E_CPU0_PE3_OCP_RXN<11>")
		)
		(pad "94" smd rect
			(at 4.787646 36.800028 270)
			(size 2.3876 0.508)
			(layers "F.Cu" "F.Mask" "F.Paste")
			(net "GND")
		)
		(pad "95" smd rect
			(at 0 37.599874 270)
			(size 2.3876 0.508)
			(layers "F.Cu" "F.Mask" "F.Paste")
			(net "GND")
		)
		(pad "96" smd rect
			(at 4.787646 37.599874 270)
			(size 2.3876 0.508)
			(layers "F.Cu" "F.Mask" "F.Paste")
			(net "P3E_OCP_CPU0_PE3_C_TXP<10>")
		)
		(pad "97" smd rect
			(at 0 38.399974 270)
			(size 2.3876 0.508)
			(layers "F.Cu" "F.Mask" "F.Paste")
			(net "GND")
		)
		(pad "98" smd rect
			(at 4.787646 38.399974 270)
			(size 2.3876 0.508)
			(layers "F.Cu" "F.Mask" "F.Paste")
			(net "P3E_OCP_CPU0_PE3_C_TXN<10>")
		)
		(pad "99" smd rect
			(at 0 39.200074 270)
			(size 2.3876 0.508)
			(layers "F.Cu" "F.Mask" "F.Paste")
			(net "P3E_CPU0_PE3_OCP_RXP<10>")
		)
		(pad "100" smd rect
			(at 4.787646 39.200074 270)
			(size 2.3876 0.508)
			(layers "F.Cu" "F.Mask" "F.Paste")
			(net "GND")
		)
		(pad "101" smd rect
			(at 0 39.99992 270)
			(size 2.3876 0.508)
			(layers "F.Cu" "F.Mask" "F.Paste")
			(net "P3E_CPU0_PE3_OCP_RXN<10>")
		)
		(pad "102" smd rect
			(at 4.787646 39.99992 270)
			(size 2.3876 0.508)
			(layers "F.Cu" "F.Mask" "F.Paste")
			(net "GND")
		)
		(pad "103" smd rect
			(at 0 40.80002 270)
			(size 2.3876 0.508)
			(layers "F.Cu" "F.Mask" "F.Paste")
			(net "GND")
		)
		(pad "104" smd rect
			(at 4.787646 40.80002 270)
			(size 2.3876 0.508)
			(layers "F.Cu" "F.Mask" "F.Paste")
			(net "P3E_OCP_CPU0_PE3_C_TXP<9>")
		)
		(pad "105" smd rect
			(at 0 41.60012 270)
			(size 2.3876 0.508)
			(layers "F.Cu" "F.Mask" "F.Paste")
			(net "GND")
		)
		(pad "106" smd rect
			(at 4.787646 41.60012 270)
			(size 2.3876 0.508)
			(layers "F.Cu" "F.Mask" "F.Paste")
			(net "P3E_OCP_CPU0_PE3_C_TXN<9>")
		)
		(pad "107" smd rect
			(at 0 42.399966 270)
			(size 2.3876 0.508)
			(layers "F.Cu" "F.Mask" "F.Paste")
			(net "P3E_CPU0_PE3_OCP_RXP<9>")
		)
		(pad "108" smd rect
			(at 4.787646 42.399966 270)
			(size 2.3876 0.508)
			(layers "F.Cu" "F.Mask" "F.Paste")
			(net "GND")
		)
		(pad "109" smd rect
			(at 0 43.200066 270)
			(size 2.3876 0.508)
			(layers "F.Cu" "F.Mask" "F.Paste")
			(net "P3E_CPU0_PE3_OCP_RXN<9>")
		)
		(pad "110" smd rect
			(at 4.787646 43.200066 270)
			(size 2.3876 0.508)
			(layers "F.Cu" "F.Mask" "F.Paste")
			(net "GND")
		)
		(pad "111" smd rect
			(at 0 43.999912 270)
			(size 2.3876 0.508)
			(layers "F.Cu" "F.Mask" "F.Paste")
			(net "GND")
		)
		(pad "112" smd rect
			(at 4.787646 43.999912 270)
			(size 2.3876 0.508)
			(layers "F.Cu" "F.Mask" "F.Paste")
			(net "P3E_OCP_CPU0_PE3_C_TXP<8>")
		)
		(pad "113" smd rect
			(at 0 44.800012 270)
			(size 2.3876 0.508)
			(layers "F.Cu" "F.Mask" "F.Paste")
			(net "GND")
		)
		(pad "114" smd rect
			(at 4.787646 44.800012 270)
			(size 2.3876 0.508)
			(layers "F.Cu" "F.Mask" "F.Paste")
			(net "P3E_OCP_CPU0_PE3_C_TXN<8>")
		)
		(pad "115" smd rect
			(at 0 45.600112 270)
			(size 2.3876 0.508)
			(layers "F.Cu" "F.Mask" "F.Paste")
			(net "P3E_CPU0_PE3_OCP_RXP<8>")
		)
	)
)
